# S9S_MB_2U (Grand Teton) — schematic netlist excerpt (pin names and nets, part order shuffled) for the footprints in the layout excerpt that follows; sources: Cadence DE-HDL packaged netlist, KiCad conversion of 03242023_DA0F0TMBIJ0_F0T_Motherboard_J_brd_V01_OCP.brd

R678  Q_RES  1K 1% CHIP  pkg 0402LF  page 229 : A = PD_I3C_SPD_DDR_CPU0_OE_N ; B = GND
R2503  Q_RES  33.2 1% CHIP  pkg 0402LF  page 115 : A = PWRGD_FAIL_CPU1_CD_R1 ; B = PWRGD_FAIL_CPU1_CD_R

(kicad_pcb
	(version 20260206)
	(generator "pcbnew")
	(generator_version "10.0")
	(general
		(thickness 1.6)
		(legacy_teardrops no)
	)
	(paper "A4")
	(title_block
		(title "03242023_DA0F0TMBIJ0_F0T_Motherboard_J_brd_V01_OCP.brd")
		(comment 1 "Grand Teton / footprints 5913-5914 of 6105")
	)
	(layers
		(0 "F.Cu" signal "TOP")
		(4 "In1.Cu" signal "GND")
		(6 "In2.Cu" signal "IN1")
		(8 "In3.Cu" signal "GND1")
		(10 "In4.Cu" signal "IN2")
		(12 "In5.Cu" signal "GND2")
		(14 "In6.Cu" signal "IN3")
		(16 "In7.Cu" signal "GND3")
		(18 "In8.Cu" signal "VCC")
		(20 "In9.Cu" signal "VCC1")
		(22 "In10.Cu" signal "GND4")
		(24 "In11.Cu" signal "IN4")
		(26 "In12.Cu" signal "GND5")
		(28 "In13.Cu" signal "IN5")
		(30 "In14.Cu" signal "GND6")
		(32 "In15.Cu" signal "IN6")
		(34 "In16.Cu" signal "GND7")
		(2 "B.Cu" signal "BOTTOM")
		(9 "F.Adhes" user "F.Adhesive")
		(11 "B.Adhes" user "B.Adhesive")
		(13 "F.Paste" user "Package Geometry/Pastemask Top")
		(15 "B.Paste" user "Package Geometry/Pastemask Bottom")
		(5 "F.SilkS" user "Ref Des/Silkscreen Top")
		(7 "B.SilkS" user "Ref Des/Silkscreen Bottom")
		(1 "F.Mask" user "Board Geometry/Soldermask Top")
		(3 "B.Mask" user "Board Geometry/Soldermask Bottom")
		(17 "Dwgs.User" user "User.Drawings")
		(19 "Cmts.User" user "User.Comments")
		(21 "Eco1.User" user "User.Eco1")
		(23 "Eco2.User" user "User.Eco2")
		(25 "Edge.Cuts" user "Board Geometry/Outline")
		(27 "Margin" user)
		(31 "F.CrtYd" user "Package Geometry/Place Bound Top")
		(29 "B.CrtYd" user "Package Geometry/Place Bound Bottom")
		(35 "F.Fab" user "Ref Des/Assembly Top")
		(33 "B.Fab" user "Ref Des/Assembly Bottom")
	)
	(footprint ""
		(layer "B.Cu")
		(at 305.589432 -149.533356)
		(property "Reference" "R678"
			(at 0 0 0)
			(layer "B.SilkS")
			(hide yes)
			(effects
				(font
					(size 1.27 1.27)
				)
				(justify mirror)
			)
		)
		(property "Value" ""
			(at 0 0 0)
			(layer "B.Fab")
			(effects
				(font
					(size 1.27 1.27)
				)
				(justify mirror)
			)
		)
		(duplicate_pad_numbers_are_jumpers no)
		(fp_line
			(start -0.7874 -0.4064)
			(end -0.7874 0.4064)
			(stroke
				(width 0.1524)
				(type default)
			)
			(layer "B.SilkS")
		)
		(fp_line
			(start -0.7874 0.4064)
			(end 0.7874 0.4064)
			(stroke
				(width 0.1524)
				(type default)
			)
			(layer "B.SilkS")
		)
		(fp_line
			(start 0.7874 -0.4064)
			(end -0.7874 -0.4064)
			(stroke
				(width 0.1524)
				(type default)
			)
			(layer "B.SilkS")
		)
		(fp_line
			(start 0.7874 0.4064)
			(end 0.7874 -0.4064)
			(stroke
				(width 0.1524)
				(type default)
			)
			(layer "B.SilkS")
		)
		(fp_line
			(start -0.67945 -0.3048)
			(end -0.67945 0.3048)
			(stroke
				(width 0.1)
				(type default)
			)
			(layer "B.Fab")
		)
		(fp_line
			(start -0.67945 0.3048)
			(end -0.120396 0.3048)
			(stroke
				(width 0.1)
				(type default)
			)
			(layer "B.Fab")
		)
		(fp_line
			(start -0.12065 -0.3048)
			(end -0.67945 -0.3048)
			(stroke
				(width 0.1)
				(type default)
			)
			(layer "B.Fab")
		)
		(fp_line
			(start -0.12065 -0.2794)
			(end -0.12065 -0.3048)
			(stroke
				(width 0.1)
				(type default)
			)
			(layer "B.Fab")
		)
		(fp_line
			(start -0.120396 0.2794)
			(end 0.12065 0.2794)
			(stroke
				(width 0.1)
				(type default)
			)
			(layer "B.Fab")
		)
		(fp_line
			(start -0.120396 0.3048)
			(end -0.120396 0.2794)
			(stroke
				(width 0.1)
				(type default)
			)
			(layer "B.Fab")
		)
		(fp_line
			(start 0.12065 -0.305054)
			(end 0.12065 -0.2794)
			(stroke
				(width 0.1)
				(type default)
			)
			(layer "B.Fab")
		)
		(fp_line
			(start 0.12065 -0.2794)
			(end -0.12065 -0.2794)
			(stroke
				(width 0.1)
				(type default)
			)
			(layer "B.Fab")
		)
		(fp_line
			(start 0.12065 0.2794)
			(end 0.12065 0.3048)
			(stroke
				(width 0.1)
				(type default)
			)
			(layer "B.Fab")
		)
		(fp_line
			(start 0.12065 0.3048)
			(end 0.67945 0.3048)
			(stroke
				(width 0.1)
				(type default)
			)
			(layer "B.Fab")
		)
		(fp_line
			(start 0.67945 -0.305054)
			(end 0.12065 -0.305054)
			(stroke
				(width 0.1)
				(type default)
			)
			(layer "B.Fab")
		)
		(fp_line
			(start 0.67945 0.3048)
			(end 0.67945 -0.305054)
			(stroke
				(width 0.1)
				(type default)
			)
			(layer "B.Fab")
		)
		(pad "1" smd circle
			(at 0.40005 0 180)
			(size 0 0)
			(layers "B.Cu" "B.Mask" "B.Paste")
			(net "PD_I3C_SPD_DDR_CPU0_OE_N")
		)
		(pad "2" smd circle
			(at -0.40005 0 180)
			(size 0 0)
			(layers "B.Cu" "B.Mask" "B.Paste")
			(net "GND")
		)
	)
	(footprint ""
		(layer "B.Cu")
		(at 40.436038 -313.866784 90)
		(property "Reference" "R2503"
			(at 0 0 90)
			(layer "B.SilkS")
			(hide yes)
			(effects
				(font
					(size 1.27 1.27)
				)
				(justify mirror)
			)
		)
		(property "Value" ""
			(at 0 0 90)
			(layer "B.Fab")
			(effects
				(font
					(size 1.27 1.27)
				)
				(justify mirror)
			)
		)
		(duplicate_pad_numbers_are_jumpers no)
		(fp_line
			(start 0.7874 -0.4064)
			(end -0.7874 -0.4064)
			(stroke
				(width 0.1524)
				(type default)
			)
			(layer "B.SilkS")
		)
		(fp_line
			(start -0.7874 -0.4064)
			(end -0.7874 0.4064)
			(stroke
				(width 0.1524)
				(type default)
			)
			(layer "B.SilkS")
		)
		(fp_line
			(start 0.7874 0.4064)
			(end 0.7874 -0.4064)
			(stroke
				(width 0.1524)
				(type default)
			)
			(layer "B.SilkS")
		)
		(fp_line
			(start -0.7874 0.4064)
			(end 0.7874 0.4064)
			(stroke
				(width 0.1524)
				(type default)
			)
			(layer "B.SilkS")
		)
		(fp_line
			(start 0.67945 -0.305054)
			(end 0.12065 -0.305054)
			(stroke
				(width 0.1)
				(type default)
			)
			(layer "B.Fab")
		)
		(fp_line
			(start 0.12065 -0.305054)
			(end 0.12065 -0.2794)
			(stroke
				(width 0.1)
				(type default)
			)
			(layer "B.Fab")
		)
		(fp_line
			(start -0.12065 -0.3048)
			(end -0.67945 -0.3048)
			(stroke
				(width 0.1)
				(type default)
			)
			(layer "B.Fab")
		)
		(fp_line
			(start -0.67945 -0.3048)
			(end -0.67945 0.3048)
			(stroke
				(width 0.1)
				(type default)
			)
			(layer "B.Fab")
		)
		(fp_line
			(start 0.12065 -0.2794)
			(end -0.12065 -0.2794)
			(stroke
				(width 0.1)
				(type default)
			)
			(layer "B.Fab")
		)
		(fp_line
			(start -0.12065 -0.2794)
			(end -0.12065 -0.3048)
			(stroke
				(width 0.1)
				(type default)
			)
			(layer "B.Fab")
		)
		(fp_line
			(start 0.12065 0.2794)
			(end 0.12065 0.3048)
			(stroke
				(width 0.1)
				(type default)
			)
			(layer "B.Fab")
		)
		(fp_line
			(start -0.120396 0.2794)
			(end 0.12065 0.2794)
			(stroke
				(width 0.1)
				(type default)
			)
			(layer "B.Fab")
		)
		(fp_line
			(start 0.67945 0.3048)
			(end 0.67945 -0.305054)
			(stroke
				(width 0.1)
				(type default)
			)
			(layer "B.Fab")
		)
		(fp_line
			(start 0.12065 0.3048)
			(end 0.67945 0.3048)
			(stroke
				(width 0.1)
				(type default)
			)
			(layer "B.Fab")
		)
		(fp_line
			(start -0.120396 0.3048)
			(end -0.120396 0.2794)
			(stroke
				(width 0.1)
				(type default)
			)
			(layer "B.Fab")
		)
		(fp_line
			(start -0.67945 0.3048)
			(end -0.120396 0.3048)
			(stroke
				(width 0.1)
				(type default)
			)
			(layer "B.Fab")
		)
		(pad "1" smd circle
			(at 0.40005 0 270)
			(size 0 0)
			(layers "B.Cu" "B.Mask" "B.Paste")
			(net "PWRGD_FAIL_CPU1_CD_R1")
		)
		(pad "2" smd circle
			(at -0.40005 0 270)
			(size 0 0)
			(layers "B.Cu" "B.Mask" "B.Paste")
			(net "PWRGD_FAIL_CPU1_CD_R")
		)
	)
)
